(kicad_pcb
	(version 20260206)
	(generator "pcbnew")
	(generator_version "10.0")
	(general
		(thickness 1.6)
		(legacy_teardrops no)
	)
	(paper "A4")
	(title_block
		(title "01162023_DA0F0TEBIF0_F0T_Expander_BD_F_brd_V02_OCP.brd")
		(comment 1 "Grand Teton / footprints 3615-3621 of 9728")
	)
	(layers
		(0 "F.Cu" signal "TOP")
		(4 "In1.Cu" signal "GND")
		(6 "In2.Cu" signal "VCC")
		(8 "In3.Cu" signal "VCC1")
		(10 "In4.Cu" signal "GND1")
		(12 "In5.Cu" signal "IN1")
		(14 "In6.Cu" signal "GND2")
		(16 "In7.Cu" signal "IN2")
		(18 "In8.Cu" signal "GND3")
		(20 "In9.Cu" signal "IN3")
		(22 "In10.Cu" signal "GND4")
		(24 "In11.Cu" signal "IN4")
		(26 "In12.Cu" signal "GND5")
		(28 "In13.Cu" signal "IN5")
		(30 "In14.Cu" signal "GND6")
		(32 "In15.Cu" signal "IN6")
		(34 "In16.Cu" signal "GND7")
		(2 "B.Cu" signal "BOTTOM")
		(9 "F.Adhes" user "F.Adhesive")
		(11 "B.Adhes" user "B.Adhesive")
		(13 "F.Paste" user "Package Geometry/Pastemask Top")
		(15 "B.Paste" user "Package Geometry/Pastemask Bottom")
		(5 "F.SilkS" user "Ref Des/Silkscreen Top")
		(7 "B.SilkS" user "Ref Des/Silkscreen Bottom")
		(1 "F.Mask" user "Board Geometry/Soldermask Top")
		(3 "B.Mask" user "Board Geometry/Soldermask Bottom")
		(17 "Dwgs.User" user "User.Drawings")
		(19 "Cmts.User" user "User.Comments")
		(21 "Eco1.User" user "User.Eco1")
		(23 "Eco2.User" user "User.Eco2")
		(25 "Edge.Cuts" user "Board Geometry/Outline")
		(27 "Margin" user)
		(31 "F.CrtYd" user "Package Geometry/Place Bound Top")
		(29 "B.CrtYd" user "Package Geometry/Place Bound Bottom")
		(35 "F.Fab" user "Ref Des/Assembly Top")
		(33 "B.Fab" user "Ref Des/Assembly Bottom")
	)
	(footprint ""
		(layer "F.Cu")
		(at 125.34519 -110.722918 90)
		(property "Reference" "R5829"
			(at 0 0 90)
			(layer "F.SilkS")
			(hide yes)
			(effects
				(font
					(size 1.27 1.27)
				)
			)
		)
		(property "Value" ""
			(at 0 0 90)
			(layer "F.Fab")
			(effects
				(font
					(size 1.27 1.27)
				)
			)
		)
		(duplicate_pad_numbers_are_jumpers no)
		(fp_line
			(start 0.7874 -0.4064)
			(end 0.7874 0.4064)
			(stroke
				(width 0.1524)
				(type default)
			)
			(layer "F.SilkS")
		)
		(fp_line
			(start -0.7874 -0.4064)
			(end 0.7874 -0.4064)
			(stroke
				(width 0.1524)
				(type default)
			)
			(layer "F.SilkS")
		)
		(fp_line
			(start 0.7874 0.4064)
			(end -0.7874 0.4064)
			(stroke
				(width 0.1524)
				(type default)
			)
			(layer "F.SilkS")
		)
		(fp_line
			(start -0.7874 0.4064)
			(end -0.7874 -0.4064)
			(stroke
				(width 0.1524)
				(type default)
			)
			(layer "F.SilkS")
		)
		(fp_line
			(start -0.12065 -0.305054)
			(end -0.12065 -0.2794)
			(stroke
				(width 0.1)
				(type default)
			)
			(layer "F.Fab")
		)
		(fp_line
			(start -0.67945 -0.305054)
			(end -0.12065 -0.305054)
			(stroke
				(width 0.1)
				(type default)
			)
			(layer "F.Fab")
		)
		(fp_line
			(start 0.67945 -0.3048)
			(end 0.67945 0.3048)
			(stroke
				(width 0.1)
				(type default)
			)
			(layer "F.Fab")
		)
		(fp_line
			(start 0.12065 -0.3048)
			(end 0.67945 -0.3048)
			(stroke
				(width 0.1)
				(type default)
			)
			(layer "F.Fab")
		)
		(fp_line
			(start 0.12065 -0.2794)
			(end 0.12065 -0.3048)
			(stroke
				(width 0.1)
				(type default)
			)
			(layer "F.Fab")
		)
		(fp_line
			(start -0.12065 -0.2794)
			(end 0.12065 -0.2794)
			(stroke
				(width 0.1)
				(type default)
			)
			(layer "F.Fab")
		)
		(fp_line
			(start 0.120396 0.2794)
			(end -0.12065 0.2794)
			(stroke
				(width 0.1)
				(type default)
			)
			(layer "F.Fab")
		)
		(fp_line
			(start -0.12065 0.2794)
			(end -0.12065 0.3048)
			(stroke
				(width 0.1)
				(type default)
			)
			(layer "F.Fab")
		)
		(fp_line
			(start 0.67945 0.3048)
			(end 0.120396 0.3048)
			(stroke
				(width 0.1)
				(type default)
			)
			(layer "F.Fab")
		)
		(fp_line
			(start 0.120396 0.3048)
			(end 0.120396 0.2794)
			(stroke
				(width 0.1)
				(type default)
			)
			(layer "F.Fab")
		)
		(fp_line
			(start -0.12065 0.3048)
			(end -0.67945 0.3048)
			(stroke
				(width 0.1)
				(type default)
			)
			(layer "F.Fab")
		)
		(fp_line
			(start -0.67945 0.3048)
			(end -0.67945 -0.305054)
			(stroke
				(width 0.1)
				(type default)
			)
			(layer "F.Fab")
		)
		(pad "1" smd circle
			(at -0.40005 0 90)
			(size 0 0)
			(layers "F.Cu" "F.Mask" "F.Paste")
			(net "P3V3_PG_G1")
		)
		(pad "2" smd circle
			(at 0.40005 0 90)
			(size 0 0)
			(layers "F.Cu" "F.Mask" "F.Paste")
			(net "GND")
		)
	)
	(footprint ""
		(layer "F.Cu")
		(at 180.594 -187.495688 180)
		(property "Reference" "Q240"
			(at 5.220462 1.054862 0)
			(unlocked yes)
			(layer "F.SilkS")
			(effects
				(font
					(size 0.7874 0.5842)
					(thickness 0.1524)
				)
				(justify left)
			)
		)
		(property "Value" ""
			(at 0 0 180)
			(layer "F.Fab")
			(effects
				(font
					(size 1.27 1.27)
				)
			)
		)
		(duplicate_pad_numbers_are_jumpers no)
		(fp_line
			(start 1.603248 1.500124)
			(end -1.603248 1.500124)
			(stroke
				(width 0.1524)
				(type default)
			)
			(layer "F.SilkS")
		)
		(fp_line
			(start 1.603248 -1.500124)
			(end 1.603248 1.500124)
			(stroke
				(width 0.1524)
				(type default)
			)
			(layer "F.SilkS")
		)
		(fp_line
			(start -1.603248 1.500124)
			(end -1.603248 -1.500124)
			(stroke
				(width 0.1524)
				(type default)
			)
			(layer "F.SilkS")
		)
		(fp_line
			(start -1.603248 -1.500124)
			(end 1.603248 -1.500124)
			(stroke
				(width 0.1524)
				(type default)
			)
			(layer "F.SilkS")
		)
		(fp_line
			(start 1.249934 0.219964)
			(end 1.249934 -0.219964)
			(stroke
				(width 0.1)
				(type default)
			)
			(layer "F.Fab")
		)
		(fp_line
			(start 1.249934 -0.219964)
			(end 0.700024 -0.219964)
			(stroke
				(width 0.1)
				(type default)
			)
			(layer "F.Fab")
		)
		(fp_line
			(start 0.700024 1.500124)
			(end 0.700024 0.219964)
			(stroke
				(width 0.1)
				(type default)
			)
			(layer "F.Fab")
		)
		(fp_line
			(start 0.700024 0.219964)
			(end 1.249934 0.219964)
			(stroke
				(width 0.1)
				(type default)
			)
			(layer "F.Fab")
		)
		(fp_line
			(start 0.700024 -0.219964)
			(end 0.700024 -1.500124)
			(stroke
				(width 0.1)
				(type default)
			)
			(layer "F.Fab")
		)
		(fp_line
			(start 0.700024 -1.500124)
			(end -0.700024 -1.500124)
			(stroke
				(width 0.1)
				(type default)
			)
			(layer "F.Fab")
		)
		(fp_line
			(start -0.6985 0.729996)
			(end -1.249934 0.729996)
			(stroke
				(width 0.1)
				(type default)
			)
			(layer "F.Fab")
		)
		(fp_line
			(start -0.6985 -0.729996)
			(end -0.6985 0.729996)
			(stroke
				(width 0.1)
				(type default)
			)
			(layer "F.Fab")
		)
		(fp_line
			(start -0.700024 1.500124)
			(end 0.700024 1.500124)
			(stroke
				(width 0.1)
				(type default)
			)
			(layer "F.Fab")
		)
		(fp_line
			(start -0.700024 1.169924)
			(end -0.700024 1.500124)
			(stroke
				(width 0.1)
				(type default)
			)
			(layer "F.Fab")
		)
		(fp_line
			(start -0.700024 -1.169924)
			(end -1.249934 -1.169924)
			(stroke
				(width 0.1)
				(type default)
			)
			(layer "F.Fab")
		)
		(fp_line
			(start -0.700024 -1.500124)
			(end -0.700024 -1.169924)
			(stroke
				(width 0.1)
				(type default)
			)
			(layer "F.Fab")
		)
		(fp_line
			(start -1.249934 1.169924)
			(end -0.700024 1.169924)
			(stroke
				(width 0.1)
				(type default)
			)
			(layer "F.Fab")
		)
		(fp_line
			(start -1.249934 0.729996)
			(end -1.249934 1.169924)
			(stroke
				(width 0.1)
				(type default)
			)
			(layer "F.Fab")
		)
		(fp_line
			(start -1.249934 -0.729996)
			(end -0.6985 -0.729996)
			(stroke
				(width 0.1)
				(type default)
			)
			(layer "F.Fab")
		)
		(fp_line
			(start -1.249934 -1.169924)
			(end -1.249934 -0.729996)
			(stroke
				(width 0.1)
				(type default)
			)
			(layer "F.Fab")
		)
		(fp_rect
			(start -0.700024 1.500124)
			(end 0.700024 -1.500124)
			(stroke
				(width 0)
				(type default)
			)
			(fill no)
			(layer "F.Fab")
		)
		(pad "D" smd rect
			(at 0.999998 0 90)
			(size 0.8128 0.9144)
			(layers "F.Cu" "F.Mask" "F.Paste")
			(net "SPI_BIC1_LS01_EN_N")
		)
		(pad "G" smd rect
			(at -0.999998 -0.94996 90)
			(size 0.8128 0.9144)
			(layers "F.Cu" "F.Mask" "F.Paste")
			(net "SPI_BIC1_LS01_EN")
		)
		(pad "S" smd rect
			(at -0.999998 0.94996 90)
			(size 0.8128 0.9144)
			(layers "F.Cu" "F.Mask" "F.Paste")
			(net "GND")
		)
	)
	(footprint ""
		(layer "F.Cu")
		(at 93.726 -125.530864)
		(property "Reference" "PC461"
			(at 0 0 0)
			(layer "F.SilkS")
			(hide yes)
			(effects
				(font
					(size 1.27 1.27)
				)
			)
		)
		(property "Value" ""
			(at 0 0 0)
			(layer "F.Fab")
			(effects
				(font
					(size 1.27 1.27)
				)
			)
		)
		(duplicate_pad_numbers_are_jumpers no)
		(fp_line
			(start -1.524 -0.762)
			(end 1.524 -0.762)
			(stroke
				(width 0.1524)
				(type default)
			)
			(layer "F.SilkS")
		)
		(fp_line
			(start -1.524 0.762)
			(end -1.524 -0.762)
			(stroke
				(width 0.1524)
				(type default)
			)
			(layer "F.SilkS")
		)
		(fp_line
			(start 1.524 -0.762)
			(end 1.524 0.762)
			(stroke
				(width 0.1524)
				(type default)
			)
			(layer "F.SilkS")
		)
		(fp_line
			(start 1.524 0.762)
			(end -1.524 0.762)
			(stroke
				(width 0.1524)
				(type default)
			)
			(layer "F.SilkS")
		)
		(fp_line
			(start -1.1049 -0.724916)
			(end -1.1049 0.724916)
			(stroke
				(width 0.1)
				(type default)
			)
			(layer "F.Fab")
		)
		(fp_line
			(start -1.1049 0.724916)
			(end 1.1049 0.724916)
			(stroke
				(width 0.1)
				(type default)
			)
			(layer "F.Fab")
		)
		(fp_line
			(start 1.1049 -0.724916)
			(end -1.1049 -0.724916)
			(stroke
				(width 0.1)
				(type default)
			)
			(layer "F.Fab")
		)
		(fp_line
			(start 1.1049 0.724916)
			(end 1.1049 -0.724916)
			(stroke
				(width 0.1)
				(type default)
			)
			(layer "F.Fab")
		)
		(pad "1" smd rect
			(at -0.889 0 180)
			(size 1.016 1.27)
			(layers "F.Cu" "F.Mask" "F.Paste")
			(net "GND")
		)
		(pad "2" smd rect
			(at 0.889 0 180)
			(size 1.016 1.27)
			(layers "F.Cu" "F.Mask" "F.Paste")
			(net "P3V3_AUX")
		)
	)
	(footprint ""
		(layer "F.Cu")
		(at 39.280592 -99.288854)
		(property "Reference" "C63"
			(at 0 0 0)
			(layer "F.SilkS")
			(hide yes)
			(effects
				(font
					(size 1.27 1.27)
				)
			)
		)
		(property "Value" ""
			(at 0 0 0)
			(layer "F.Fab")
			(effects
				(font
					(size 1.27 1.27)
				)
			)
		)
		(duplicate_pad_numbers_are_jumpers no)
		(fp_line
			(start -0.299974 -0.150114)
			(end 0.299974 -0.150114)
			(stroke
				(width 0.1)
				(type default)
			)
			(layer "F.Fab")
		)
		(fp_line
			(start -0.299974 0.150114)
			(end -0.299974 -0.150114)
			(stroke
				(width 0.1)
				(type default)
			)
			(layer "F.Fab")
		)
		(fp_line
			(start 0.299974 -0.150114)
			(end 0.299974 0.150114)
			(stroke
				(width 0.1)
				(type default)
			)
			(layer "F.Fab")
		)
		(fp_line
			(start 0.299974 0.150114)
			(end -0.299974 0.150114)
			(stroke
				(width 0.1)
				(type default)
			)
			(layer "F.Fab")
		)
		(pad "1" smd rect
			(at -0.2667 0)
			(size 0.3048 0.381)
			(layers "F.Cu" "F.Mask" "F.Paste")
			(net "P5E_PEX0_STN1_TX_DP<16>")
		)
		(pad "2" smd rect
			(at 0.2667 0)
			(size 0.3048 0.381)
			(layers "F.Cu" "F.Mask" "F.Paste")
			(net "P5E_PEX0_STN1_TX_C_DP<16>")
		)
	)
	(footprint ""
		(layer "F.Cu")
		(at 196.975222 -64.102234 180)
		(property "Reference" "PR7074"
			(at 0 0 180)
			(layer "F.SilkS")
			(hide yes)
			(effects
				(font
					(size 1.27 1.27)
				)
			)
		)
		(property "Value" ""
			(at 0 0 180)
			(layer "F.Fab")
			(effects
				(font
					(size 1.27 1.27)
				)
			)
		)
		(duplicate_pad_numbers_are_jumpers no)
		(fp_line
			(start 0.7874 0.4064)
			(end -0.7874 0.4064)
			(stroke
				(width 0.1524)
				(type default)
			)
			(layer "F.SilkS")
		)
		(fp_line
			(start 0.7874 -0.4064)
			(end 0.7874 0.4064)
			(stroke
				(width 0.1524)
				(type default)
			)
			(layer "F.SilkS")
		)
		(fp_line
			(start -0.7874 0.4064)
			(end -0.7874 -0.4064)
			(stroke
				(width 0.1524)
				(type default)
			)
			(layer "F.SilkS")
		)
		(fp_line
			(start -0.7874 -0.4064)
			(end 0.7874 -0.4064)
			(stroke
				(width 0.1524)
				(type default)
			)
			(layer "F.SilkS")
		)
		(fp_line
			(start 0.67945 0.3048)
			(end 0.120396 0.3048)
			(stroke
				(width 0.1)
				(type default)
			)
			(layer "F.Fab")
		)
		(fp_line
			(start 0.67945 -0.3048)
			(end 0.67945 0.3048)
			(stroke
				(width 0.1)
				(type default)
			)
			(layer "F.Fab")
		)
		(fp_line
			(start 0.12065 -0.2794)
			(end 0.12065 -0.3048)
			(stroke
				(width 0.1)
				(type default)
			)
			(layer "F.Fab")
		)
		(fp_line
			(start 0.12065 -0.3048)
			(end 0.67945 -0.3048)
			(stroke
				(width 0.1)
				(type default)
			)
			(layer "F.Fab")
		)
		(fp_line
			(start 0.120396 0.3048)
			(end 0.120396 0.2794)
			(stroke
				(width 0.1)
				(type default)
			)
			(layer "F.Fab")
		)
		(fp_line
			(start 0.120396 0.2794)
			(end -0.12065 0.2794)
			(stroke
				(width 0.1)
				(type default)
			)
			(layer "F.Fab")
		)
		(fp_line
			(start -0.12065 0.3048)
			(end -0.67945 0.3048)
			(stroke
				(width 0.1)
				(type default)
			)
			(layer "F.Fab")
		)
		(fp_line
			(start -0.12065 0.2794)
			(end -0.12065 0.3048)
			(stroke
				(width 0.1)
				(type default)
			)
			(layer "F.Fab")
		)
		(fp_line
			(start -0.12065 -0.2794)
			(end 0.12065 -0.2794)
			(stroke
				(width 0.1)
				(type default)
			)
			(layer "F.Fab")
		)
		(fp_line
			(start -0.12065 -0.305054)
			(end -0.12065 -0.2794)
			(stroke
				(width 0.1)
				(type default)
			)
			(layer "F.Fab")
		)
		(fp_line
			(start -0.67945 0.3048)
			(end -0.67945 -0.305054)
			(stroke
				(width 0.1)
				(type default)
			)
			(layer "F.Fab")
		)
		(fp_line
			(start -0.67945 -0.305054)
			(end -0.12065 -0.305054)
			(stroke
				(width 0.1)
				(type default)
			)
			(layer "F.Fab")
		)
		(pad "1" smd circle
			(at -0.40005 0 180)
			(size 0 0)
			(layers "F.Cu" "F.Mask" "F.Paste")
			(net "P12V_SSD7_PG_G1")
		)
		(pad "2" smd circle
			(at 0.40005 0 180)
			(size 0 0)
			(layers "F.Cu" "F.Mask" "F.Paste")
			(net "GND")
		)
	)
	(footprint ""
		(layer "F.Cu")
		(at 344.511884 -110.515654)
		(property "Reference" "PC815"
			(at 0 0 0)
			(layer "F.SilkS")
			(hide yes)
			(effects
				(font
					(size 1.27 1.27)
				)
			)
		)
		(property "Value" ""
			(at 0 0 0)
			(layer "F.Fab")
			(effects
				(font
					(size 1.27 1.27)
				)
			)
		)
		(duplicate_pad_numbers_are_jumpers no)
		(fp_line
			(start -0.7874 -0.4064)
			(end 0.7874 -0.4064)
			(stroke
				(width 0.1524)
				(type default)
			)
			(layer "F.SilkS")
		)
		(fp_line
			(start -0.7874 0.4064)
			(end -0.7874 -0.4064)
			(stroke
				(width 0.1524)
				(type default)
			)
			(layer "F.SilkS")
		)
		(fp_line
			(start 0.7874 -0.4064)
			(end 0.7874 0.4064)
			(stroke
				(width 0.1524)
				(type default)
			)
			(layer "F.SilkS")
		)
		(fp_line
			(start 0.7874 0.4064)
			(end -0.7874 0.4064)
			(stroke
				(width 0.1524)
				(type default)
			)
			(layer "F.SilkS")
		)
		(fp_line
			(start -0.67945 -0.305054)
			(end -0.12065 -0.305054)
			(stroke
				(width 0.1)
				(type default)
			)
			(layer "F.Fab")
		)
		(fp_line
			(start -0.67945 0.3048)
			(end -0.67945 -0.305054)
			(stroke
				(width 0.1)
				(type default)
			)
			(layer "F.Fab")
		)
		(fp_line
			(start -0.12065 -0.305054)
			(end -0.12065 -0.2794)
			(stroke
				(width 0.1)
				(type default)
			)
			(layer "F.Fab")
		)
		(fp_line
			(start -0.12065 -0.2794)
			(end 0.12065 -0.2794)
			(stroke
				(width 0.1)
				(type default)
			)
			(layer "F.Fab")
		)
		(fp_line
			(start -0.12065 0.2794)
			(end -0.12065 0.3048)
			(stroke
				(width 0.1)
				(type default)
			)
			(layer "F.Fab")
		)
		(fp_line
			(start -0.12065 0.3048)
			(end -0.67945 0.3048)
			(stroke
				(width 0.1)
				(type default)
			)
			(layer "F.Fab")
		)
		(fp_line
			(start 0.120396 0.2794)
			(end -0.12065 0.2794)
			(stroke
				(width 0.1)
				(type default)
			)
			(layer "F.Fab")
		)
		(fp_line
			(start 0.120396 0.3048)
			(end 0.120396 0.2794)
			(stroke
				(width 0.1)
				(type default)
			)
			(layer "F.Fab")
		)
		(fp_line
			(start 0.12065 -0.3048)
			(end 0.67945 -0.3048)
			(stroke
				(width 0.1)
				(type default)
			)
			(layer "F.Fab")
		)
		(fp_line
			(start 0.12065 -0.2794)
			(end 0.12065 -0.3048)
			(stroke
				(width 0.1)
				(type default)
			)
			(layer "F.Fab")
		)
		(fp_line
			(start 0.67945 -0.3048)
			(end 0.67945 0.3048)
			(stroke
				(width 0.1)
				(type default)
			)
			(layer "F.Fab")
		)
		(fp_line
			(start 0.67945 0.3048)
			(end 0.120396 0.3048)
			(stroke
				(width 0.1)
				(type default)
			)
			(layer "F.Fab")
		)
		(pad "1" smd circle
			(at -0.40005 0)
			(size 0 0)
			(layers "F.Cu" "F.Mask" "F.Paste")
			(net "P12V_NIC5_CO_TIMER")
		)
		(pad "2" smd circle
			(at 0.40005 0)
			(size 0 0)
			(layers "F.Cu" "F.Mask" "F.Paste")
			(net "GND")
		)
	)
	(footprint ""
		(layer "F.Cu")
		(at 154.699716 -150.263352 180)
		(property "Reference" "R117"
			(at 0 0 180)
			(layer "F.SilkS")
			(hide yes)
			(effects
				(font
					(size 1.27 1.27)
				)
			)
		)
		(property "Value" ""
			(at 0 0 180)
			(layer "F.Fab")
			(effects
				(font
					(size 1.27 1.27)
				)
			)
		)
		(duplicate_pad_numbers_are_jumpers no)
		(fp_line
			(start 0.7874 0.4064)
			(end -0.7874 0.4064)
			(stroke
				(width 0.1524)
				(type default)
			)
			(layer "F.SilkS")
		)
		(fp_line
			(start 0.7874 -0.4064)
			(end 0.7874 0.4064)
			(stroke
				(width 0.1524)
				(type default)
			)
			(layer "F.SilkS")
		)
		(fp_line
			(start -0.7874 0.4064)
			(end -0.7874 -0.4064)
			(stroke
				(width 0.1524)
				(type default)
			)
			(layer "F.SilkS")
		)
		(fp_line
			(start -0.7874 -0.4064)
			(end 0.7874 -0.4064)
			(stroke
				(width 0.1524)
				(type default)
			)
			(layer "F.SilkS")
		)
		(fp_line
			(start 0.67945 0.3048)
			(end 0.120396 0.3048)
			(stroke
				(width 0.1)
				(type default)
			)
			(layer "F.Fab")
		)
		(fp_line
			(start 0.67945 -0.3048)
			(end 0.67945 0.3048)
			(stroke
				(width 0.1)
				(type default)
			)
			(layer "F.Fab")
		)
		(fp_line
			(start 0.12065 -0.2794)
			(end 0.12065 -0.3048)
			(stroke
				(width 0.1)
				(type default)
			)
			(layer "F.Fab")
		)
		(fp_line
			(start 0.12065 -0.3048)
			(end 0.67945 -0.3048)
			(stroke
				(width 0.1)
				(type default)
			)
			(layer "F.Fab")
		)
		(fp_line
			(start 0.120396 0.3048)
			(end 0.120396 0.2794)
			(stroke
				(width 0.1)
				(type default)
			)
			(layer "F.Fab")
		)
		(fp_line
			(start 0.120396 0.2794)
			(end -0.12065 0.2794)
			(stroke
				(width 0.1)
				(type default)
			)
			(layer "F.Fab")
		)
		(fp_line
			(start -0.12065 0.3048)
			(end -0.67945 0.3048)
			(stroke
				(width 0.1)
				(type default)
			)
			(layer "F.Fab")
		)
		(fp_line
			(start -0.12065 0.2794)
			(end -0.12065 0.3048)
			(stroke
				(width 0.1)
				(type default)
			)
			(layer "F.Fab")
		)
		(fp_line
			(start -0.12065 -0.2794)
			(end 0.12065 -0.2794)
			(stroke
				(width 0.1)
				(type default)
			)
			(layer "F.Fab")
		)
		(fp_line
			(start -0.12065 -0.305054)
			(end -0.12065 -0.2794)
			(stroke
				(width 0.1)
				(type default)
			)
			(layer "F.Fab")
		)
		(fp_line
			(start -0.67945 0.3048)
			(end -0.67945 -0.305054)
			(stroke
				(width 0.1)
				(type default)
			)
			(layer "F.Fab")
		)
		(fp_line
			(start -0.67945 -0.305054)
			(end -0.12065 -0.305054)
			(stroke
				(width 0.1)
				(type default)
			)
			(layer "F.Fab")
		)
		(pad "1" smd circle
			(at -0.40005 0 180)
			(size 0 0)
			(layers "F.Cu" "F.Mask" "F.Paste")
			(net "NCSI_NIC2_CRS_DV")
		)
		(pad "2" smd circle
			(at 0.40005 0 180)
			(size 0 0)
			(layers "F.Cu" "F.Mask" "F.Paste")
			(net "GND")
		)
	)
)
